(kicad_pcb
	(version 20241229)
	(generator "pcbnew")
	(generator_version "9.0")
	(general
		(thickness 1.552)
		(legacy_teardrops no)
	)
	(paper "A4")
	(title_block
		(date "2023-07-25")
		(rev "1.1.4")
		(comment 9 "footprint 14 of 379 (U11), pads 166-245 of 256")
	)
	(layers
		(0 "F.Cu" signal)
		(4 "In1.Cu" signal)
		(6 "In2.Cu" signal)
		(8 "In3.Cu" signal)
		(10 "In4.Cu" signal)
		(12 "In5.Cu" signal)
		(14 "In6.Cu" signal)
		(2 "B.Cu" signal)
		(9 "F.Adhes" user "F.Adhesive")
		(11 "B.Adhes" user "B.Adhesive")
		(13 "F.Paste" user)
		(15 "B.Paste" user)
		(5 "F.SilkS" user "F.Silkscreen")
		(7 "B.SilkS" user "B.Silkscreen")
		(1 "F.Mask" user)
		(3 "B.Mask" user)
		(17 "Dwgs.User" user "User.Drawings")
		(19 "Cmts.User" user "User.Comments")
		(21 "Eco1.User" user "User.Eco1")
		(23 "Eco2.User" user "User.Eco2")
		(25 "Edge.Cuts" user)
		(27 "Margin" user)
		(31 "F.CrtYd" user "F.Courtyard")
		(29 "B.CrtYd" user "B.Courtyard")
		(35 "F.Fab" user)
		(33 "B.Fab" user)
	)
	(footprint "antmicro-footprints:BGA-256_14x14mm_Layout16x16_P0.8mm"
		(locked yes)
		(layer "F.Cu")
		(at 126.3 90.3 180)
		(property "Reference" "U11"
			(at 0 -8 180)
			(layer "F.SilkS")
			(effects
				(font
					(size 0.7 0.7)
					(thickness 0.15)
				)
				(justify left bottom)
			)
		)
		(property "Value" "LIFCL-40-9BG256C"
			(at -8 8.55 180)
			(layer "F.Fab")
			(effects
				(font
					(size 0.7 0.7)
					(thickness 0.15)
				)
				(justify left bottom)
			)
		)
		(property "Datasheet" "https://www.latticesemi.com/-/media/LatticeSemi/Documents/DataSheets/CrossLink/FPGA-DS-02007-2-1-CrossLink-Family-Data-Sheet.ashx?document_id=51662"
			(at 0 0 180)
			(layer "F.Fab")
			(hide yes)
			(effects
				(font
					(size 1.27 1.27)
					(thickness 0.15)
				)
			)
		)
		(property "Description" "CrossLink-NX™ Field Programmable Gate Array 256-LFBGA"
			(at 0 0 180)
			(layer "F.Fab")
			(hide yes)
			(effects
				(font
					(size 1.27 1.27)
					(thickness 0.15)
				)
			)
		)
		(property "Author" "Antmicro"
			(at 252.6 180.6 0)
			(layer "F.Fab")
			(hide yes)
			(effects
				(font
					(size 1 1)
					(thickness 0.15)
				)
			)
		)
		(property "License" "Apache-2.0"
			(at 252.6 180.6 0)
			(layer "F.Fab")
			(hide yes)
			(effects
				(font
					(size 1 1)
					(thickness 0.15)
				)
			)
		)
		(property "MPN" "LIFCL-40-9BG256C"
			(at 252.6 180.6 0)
			(layer "F.Fab")
			(hide yes)
			(effects
				(font
					(size 1 1)
					(thickness 0.15)
				)
			)
		)
		(property "Manufacturer" "Lattice Semiconductor"
			(at 252.6 180.6 0)
			(layer "F.Fab")
			(hide yes)
			(effects
				(font
					(size 1 1)
					(thickness 0.15)
				)
			)
		)
		(sheetname "/DDR3/")
		(sheetfile "ddr3.kicad_sch")
		(attr smd)
		(pad "L6" smd circle
			(at -2 2 180)
			(size 0.45 0.45)
			(layers "F.Cu" "F.Mask" "F.Paste")
			(net 79 "/Peripherals/MIPI2_D3_P")
			(pinfunction "PB10A/PCLKT5_2/ADC_CP2/COMP3P")
			(pintype "bidirectional")
		)
		(pad "L7" smd circle
			(at -1.2 2 180)
			(size 0.45 0.45)
			(layers "F.Cu" "F.Mask" "F.Paste")
			(net 81 "/Peripherals/MIPI2_D2_P")
			(pinfunction "PB8A/PCLKT5_1/LLC_GPLL0T_IN/ADC_CP3")
			(pintype "bidirectional")
		)
		(pad "L8" smd circle
			(at -0.4 2 180)
			(size 0.45 0.45)
			(layers "F.Cu" "F.Mask" "F.Paste")
			(net 153 "/DDR3/DDR3_A9")
			(pinfunction "PB34A")
			(pintype "bidirectional")
		)
		(pad "L9" smd circle
			(at 0.4 2 180)
			(size 0.45 0.45)
			(layers "F.Cu" "F.Mask" "F.Paste")
			(net 149 "/DDR3/DDR3_A5")
			(pinfunction "PB34B")
			(pintype "bidirectional")
		)
		(pad "L10" smd circle
			(at 1.2 2 180)
			(size 0.45 0.45)
			(layers "F.Cu" "F.Mask" "F.Paste")
			(net 150 "/DDR3/DDR3_A7")
			(pinfunction "PB80B/ADC_CN12")
			(pintype "bidirectional")
		)
		(pad "L11" smd circle
			(at 2 2 180)
			(size 0.45 0.45)
			(layers "F.Cu" "F.Mask" "F.Paste")
			(net 144 "/DDR3/DDR3_A2")
			(pinfunction "PB80A/ADC_CP12")
			(pintype "bidirectional")
		)
		(pad "L12" smd circle
			(at 2.8 2 180)
			(size 0.45 0.45)
			(layers "F.Cu" "F.Mask" "F.Paste")
			(net 155 "/DDR3/DDR3_A8")
			(pinfunction "PB82B/ADC_CN15")
			(pintype "bidirectional")
		)
		(pad "L13" smd circle
			(at 3.6 2 180)
			(size 0.45 0.45)
			(layers "F.Cu" "F.Mask" "F.Paste")
			(net 1 "GND")
			(pinfunction "VSSADC")
			(pintype "power_in")
		)
		(pad "L14" smd circle
			(at 4.4 2 180)
			(size 0.45 0.45)
			(layers "F.Cu" "F.Mask" "F.Paste")
			(net 390 "unconnected-(U11K-VCCADC18-PadL14)")
			(pinfunction "VCCADC18")
			(pintype "power_in+no_connect")
		)
		(pad "L15" smd circle
			(at 5.2 2 180)
			(size 0.45 0.45)
			(layers "F.Cu" "F.Mask" "F.Paste")
			(net 1 "GND")
			(pinfunction "ADC_REFP0")
			(pintype "passive")
		)
		(pad "L16" smd circle
			(at 6 2 180)
			(size 0.45 0.45)
			(layers "F.Cu" "F.Mask" "F.Paste")
			(net 1 "GND")
			(pinfunction "ADC_REFP1")
			(pintype "passive")
		)
		(pad "M1" smd circle
			(at -6 2.8 180)
			(size 0.45 0.45)
			(layers "F.Cu" "F.Mask" "F.Paste")
			(net 218 "/SDI/SDI_STAT4")
			(pinfunction "PL42A")
			(pintype "bidirectional")
		)
		(pad "M2" smd circle
			(at -5.2 2.8 180)
			(size 0.45 0.45)
			(layers "F.Cu" "F.Mask" "F.Paste")
			(net 212 "/SDI/SDI_STAT2")
			(pinfunction "PL42B")
			(pintype "bidirectional")
		)
		(pad "M3" smd circle
			(at -4.4 2.8 180)
			(size 0.45 0.45)
			(layers "F.Cu" "F.Mask" "F.Paste")
			(net 217 "/SDI/SDI_STAT1")
			(pinfunction "PL47A")
			(pintype "bidirectional")
		)
		(pad "M4" smd circle
			(at -3.6 2.8 180)
			(size 0.45 0.45)
			(layers "F.Cu" "F.Mask" "F.Paste")
			(net 82 "/Peripherals/MIPI2_D1_N")
			(pinfunction "PB6B/PCLKC5_0/CDR_RXN1/ADC_CN1/COMP2N")
			(pintype "bidirectional")
		)
		(pad "M5" smd circle
			(at -2.8 2.8 180)
			(size 0.45 0.45)
			(layers "F.Cu" "F.Mask" "F.Paste")
			(net 1 "GND")
			(pinfunction "VSS")
			(pintype "passive")
		)
		(pad "M6" smd circle
			(at -2 2.8 180)
			(size 0.45 0.45)
			(layers "F.Cu" "F.Mask" "F.Paste")
			(net 9 "/FPGA Power/VCC_AUX")
			(pinfunction "VCCAUXH5")
			(pintype "power_in")
		)
		(pad "M7" smd circle
			(at -1.2 2.8 180)
			(size 0.45 0.45)
			(layers "F.Cu" "F.Mask" "F.Paste")
			(net 80 "/Peripherals/MIPI2_D2_N")
			(pinfunction "PB8B/PCLKC5_1/LLC_GPLL0C_IN/ADC_CN3")
			(pintype "bidirectional")
		)
		(pad "M8" smd circle
			(at -0.4 2.8 180)
			(size 0.45 0.45)
			(layers "F.Cu" "F.Mask" "F.Paste")
			(net 1 "GND")
			(pinfunction "PB38B")
			(pintype "bidirectional")
		)
		(pad "M9" smd circle
			(at 0.4 2.8 180)
			(size 0.45 0.45)
			(layers "F.Cu" "F.Mask" "F.Paste")
			(net 1 "GND")
			(pinfunction "PB38A")
			(pintype "bidirectional")
		)
		(pad "M10" smd circle
			(at 1.2 2.8 180)
			(size 0.45 0.45)
			(layers "F.Cu" "F.Mask" "F.Paste")
			(net 167 "/DDR3/DDR3_BA2")
			(pinfunction "PB46A")
			(pintype "bidirectional")
		)
		(pad "M11" smd circle
			(at 2 2.8 180)
			(size 0.45 0.45)
			(layers "F.Cu" "F.Mask" "F.Paste")
			(net 1 "GND")
			(pinfunction "PB78B/ADC_CN11")
			(pintype "bidirectional")
		)
		(pad "M12" smd circle
			(at 2.8 2.8 180)
			(size 0.45 0.45)
			(layers "F.Cu" "F.Mask" "F.Paste")
			(net 162 "/DDR3/~{DDR3_RAS}")
			(pinfunction "PB78A/ADC_CP11")
			(pintype "bidirectional")
		)
		(pad "M13" smd circle
			(at 3.6 2.8 180)
			(size 0.45 0.45)
			(layers "F.Cu" "F.Mask" "F.Paste")
			(net 148 "/DDR3/DDR3_A6")
			(pinfunction "PB82A/ADC_CP15")
			(pintype "bidirectional")
		)
		(pad "M14" smd circle
			(at 4.4 2.8 180)
			(size 0.45 0.45)
			(layers "F.Cu" "F.Mask" "F.Paste")
			(net 154 "/DDR3/DDR3_A11")
			(pinfunction "PB74A/PCLKT3_3/ADC_CP14")
			(pintype "bidirectional")
		)
		(pad "M15" smd circle
			(at 5.2 2.8 180)
			(size 0.45 0.45)
			(layers "F.Cu" "F.Mask" "F.Paste")
			(net 1 "GND")
			(pinfunction "PB84B/LRC_GPLL0C_IN/VREF3_2")
			(pintype "bidirectional")
		)
		(pad "M16" smd circle
			(at 6 2.8 180)
			(size 0.45 0.45)
			(layers "F.Cu" "F.Mask" "F.Paste")
			(net 151 "/DDR3/DDR3_A4")
			(pinfunction "PB84A/LRC_GPLL0T_IN")
			(pintype "bidirectional")
		)
		(pad "N1" smd circle
			(at -6 3.6 180)
			(size 0.45 0.45)
			(layers "F.Cu" "F.Mask" "F.Paste")
			(net 219 "/SDI/SDI_STAT3")
			(pinfunction "PL49B")
			(pintype "bidirectional")
		)
		(pad "N2" smd circle
			(at -5.2 3.6 180)
			(size 0.45 0.45)
			(layers "F.Cu" "F.Mask" "F.Paste")
			(net 214 "/SDI/SDI_STAT0")
			(pinfunction "PL49A")
			(pintype "bidirectional")
		)
		(pad "N3" smd circle
			(at -4.4 3.6 180)
			(size 0.45 0.45)
			(layers "F.Cu" "F.Mask" "F.Paste")
			(net 84 "/Peripherals/MIPI2_D0_N")
			(pinfunction "PB4B/CDR_RXN0/ADC_CN0/COMP1N")
			(pintype "bidirectional")
		)
		(pad "N4" smd circle
			(at -3.6 3.6 180)
			(size 0.45 0.45)
			(layers "F.Cu" "F.Mask" "F.Paste")
			(net 83 "/Peripherals/MIPI2_D1_P")
			(pinfunction "PB6A/PCLKT5_0/CDR_RXP1/ADC_CP1/COMP2P")
			(pintype "bidirectional")
		)
		(pad "N5" smd circle
			(at -2.8 3.6 180)
			(size 0.45 0.45)
			(layers "F.Cu" "F.Mask" "F.Paste")
			(net 3 "+1V2")
			(pinfunction "VCCIO5")
			(pintype "power_in")
		)
		(pad "N6" smd circle
			(at -2 3.6 180)
			(size 0.45 0.45)
			(layers "F.Cu" "F.Mask" "F.Paste")
			(net 248 "+1V5")
			(pinfunction "VCCIO4")
			(pintype "power_in")
		)
		(pad "N7" smd circle
			(at -1.2 3.6 180)
			(size 0.45 0.45)
			(layers "F.Cu" "F.Mask" "F.Paste")
			(net 1 "GND")
			(pinfunction "VSS")
			(pintype "passive")
		)
		(pad "N8" smd circle
			(at -0.4 3.6 180)
			(size 0.45 0.45)
			(layers "F.Cu" "F.Mask" "F.Paste")
			(net 158 "/DDR3/DDR3_A13")
			(pinfunction "PB36A")
			(pintype "bidirectional")
		)
		(pad "N9" smd circle
			(at 0.4 3.6 180)
			(size 0.45 0.45)
			(layers "F.Cu" "F.Mask" "F.Paste")
			(net 164 "/DDR3/~{DDR3_RESET}")
			(pinfunction "PB36B")
			(pintype "bidirectional")
		)
		(pad "N10" smd circle
			(at 1.2 3.6 180)
			(size 0.45 0.45)
			(layers "F.Cu" "F.Mask" "F.Paste")
			(net 168 "/DDR3/~{DDR3_CS}")
			(pinfunction "PB46B/VREF4_2")
			(pintype "bidirectional")
		)
		(pad "N11" smd circle
			(at 2 3.6 180)
			(size 0.45 0.45)
			(layers "F.Cu" "F.Mask" "F.Paste")
			(net 1 "GND")
			(pinfunction "PB64B/ADC_CN4")
			(pintype "bidirectional")
		)
		(pad "N12" smd circle
			(at 2.8 3.6 180)
			(size 0.45 0.45)
			(layers "F.Cu" "F.Mask" "F.Paste")
			(net 1 "GND")
			(pinfunction "PB64A/ADC_CP4")
			(pintype "bidirectional")
		)
		(pad "N13" smd circle
			(at 3.6 3.6 180)
			(size 0.45 0.45)
			(layers "F.Cu" "F.Mask" "F.Paste")
			(net 165 "/DDR3/DDR3_CKE")
			(pinfunction "PB70B/COMP2IN\n")
			(pintype "bidirectional")
		)
		(pad "N14" smd circle
			(at 4.4 3.6 180)
			(size 0.45 0.45)
			(layers "F.Cu" "F.Mask" "F.Paste")
			(net 1 "GND")
			(pinfunction "PB74B/PCLKC3_3/ADC_CN14")
			(pintype "bidirectional")
		)
		(pad "N15" smd circle
			(at 5.2 3.6 180)
			(size 0.45 0.45)
			(layers "F.Cu" "F.Mask" "F.Paste")
			(net 160 "/DDR3/DDR3_A12")
			(pinfunction "PB76B/COMP3IN")
			(pintype "bidirectional")
		)
		(pad "N16" smd circle
			(at 6 3.6 180)
			(size 0.45 0.45)
			(layers "F.Cu" "F.Mask" "F.Paste")
			(net 145 "/DDR3/DDR3_A1")
			(pinfunction "PB76A/COMP3IP")
			(pintype "bidirectional")
		)
		(pad "P1" smd circle
			(at -6 4.4 180)
			(size 0.45 0.45)
			(layers "F.Cu" "F.Mask" "F.Paste")
			(net 87 "/Peripherals/MIPI2_CLK_P")
			(pinfunction "PB12A/PCLKT5_3")
			(pintype "bidirectional")
		)
		(pad "P2" smd circle
			(at -5.2 4.4 180)
			(size 0.45 0.45)
			(layers "F.Cu" "F.Mask" "F.Paste")
			(net 86 "/Peripherals/MIPI2_CLK_N")
			(pinfunction "PB12B/PCLKC5_3/VREF5_2")
			(pintype "bidirectional")
		)
		(pad "P3" smd circle
			(at -4.4 4.4 180)
			(size 0.45 0.45)
			(layers "F.Cu" "F.Mask" "F.Paste")
			(net 85 "/Peripherals/MIPI2_D0_P")
			(pinfunction "PB4A/CDR_RXP0/VREF5_1/ADC_CP0/COMP1P\n")
			(pintype "bidirectional")
		)
		(pad "P4" smd circle
			(at -3.6 4.4 180)
			(size 0.45 0.45)
			(layers "F.Cu" "F.Mask" "F.Paste")
			(net 1 "GND")
			(pinfunction "PB24B/PCLKC4_2\n")
			(pintype "bidirectional")
		)
		(pad "P5" smd circle
			(at -2.8 4.4 180)
			(size 0.45 0.45)
			(layers "F.Cu" "F.Mask" "F.Paste")
			(net 220 "/DDR3/DDR3_LDQS_N")
			(pinfunction "PB22B")
			(pintype "bidirectional")
		)
		(pad "P6" smd circle
			(at -2 4.4 180)
			(size 0.45 0.45)
			(layers "F.Cu" "F.Mask" "F.Paste")
			(net 163 "/DDR3/~{DDR3_WE}")
			(pinfunction "PB32A")
			(pintype "bidirectional")
		)
		(pad "P7" smd circle
			(at -1.2 4.4 180)
			(size 0.45 0.45)
			(layers "F.Cu" "F.Mask" "F.Paste")
			(net 147 "/DDR3/DDR3_A0")
			(pinfunction "PB32B")
			(pintype "bidirectional")
		)
		(pad "P8" smd circle
			(at -0.4 4.4 180)
			(size 0.45 0.45)
			(layers "F.Cu" "F.Mask" "F.Paste")
			(net 146 "/DDR3/DDR3_A3")
			(pinfunction "PB42B")
			(pintype "bidirectional")
		)
		(pad "P9" smd circle
			(at 0.4 4.4 180)
			(size 0.45 0.45)
			(layers "F.Cu" "F.Mask" "F.Paste")
			(net 157 "/DDR3/DDR3_BA0")
			(pinfunction "PB44B/PCLKC4_0")
			(pintype "bidirectional")
		)
		(pad "P10" smd circle
			(at 1.2 4.4 180)
			(size 0.45 0.45)
			(layers "F.Cu" "F.Mask" "F.Paste")
			(net 1 "GND")
			(pinfunction "PB56A/ADC_CP7\n")
			(pintype "bidirectional")
		)
		(pad "P11" smd circle
			(at 2 4.4 180)
			(size 0.45 0.45)
			(layers "F.Cu" "F.Mask" "F.Paste")
			(net 248 "+1V5")
			(pinfunction "PB54B/PCLKC3_0/ADC_CN5\n")
			(pintype "bidirectional")
		)
		(pad "P12" smd circle
			(at 2.8 4.4 180)
			(size 0.45 0.45)
			(layers "F.Cu" "F.Mask" "F.Paste")
			(net 248 "+1V5")
			(pinfunction "VCCIO3")
			(pintype "bidirectional")
		)
		(pad "P13" smd circle
			(at 3.6 4.4 180)
			(size 0.45 0.45)
			(layers "F.Cu" "F.Mask" "F.Paste")
			(net 1 "GND")
			(pinfunction "VSS")
			(pintype "passive")
		)
		(pad "P14" smd circle
			(at 4.4 4.4 180)
			(size 0.45 0.45)
			(layers "F.Cu" "F.Mask" "F.Paste")
			(net 1 "GND")
			(pinfunction "PB70A/COMP2IP")
			(pintype "bidirectional")
		)
		(pad "P15" smd circle
			(at 5.2 4.4 180)
			(size 0.45 0.45)
			(layers "F.Cu" "F.Mask" "F.Paste")
			(net 152 "/DDR3/DDR3_A10")
			(pinfunction "PB72A/PCLKT3_2/ADC_CP13")
			(pintype "bidirectional")
		)
		(pad "P16" smd circle
			(at 6 4.4 180)
			(size 0.45 0.45)
			(layers "F.Cu" "F.Mask" "F.Paste")
			(net 159 "/DDR3/DDR3_BA1")
			(pinfunction "PB72B/PCLKC3_2/ADC_CN13")
			(pintype "bidirectional")
		)
		(pad "R1" smd circle
			(at -6 5.2 180)
			(size 0.45 0.45)
			(layers "F.Cu" "F.Mask" "F.Paste")
			(net 5 "Vref")
			(pinfunction "PB16A/VREF4_1")
			(pintype "bidirectional")
		)
		(pad "R2" smd circle
			(at -5.2 5.2 180)
			(size 0.45 0.45)
			(layers "F.Cu" "F.Mask" "F.Paste")
			(net 248 "+1V5")
			(pinfunction "PB16B")
			(pintype "bidirectional")
		)
		(pad "R3" smd circle
			(at -4.4 5.2 180)
			(size 0.45 0.45)
			(layers "F.Cu" "F.Mask" "F.Paste")
			(net 234 "/DDR3/DDR3_DQ2")
			(pinfunction "PB18A/PCLKT4_3\n")
			(pintype "bidirectional")
		)
		(pad "R4" smd circle
			(at -3.6 5.2 180)
			(size 0.45 0.45)
			(layers "F.Cu" "F.Mask" "F.Paste")
			(net 224 "/DDR3/DDR3_DQ5")
			(pinfunction "PB24A/PCLKT4_2")
			(pintype "bidirectional")
		)
		(pad "R5" smd circle
			(at -2.8 5.2 180)
			(size 0.45 0.45)
			(layers "F.Cu" "F.Mask" "F.Paste")
			(net 223 "/DDR3/DDR3_LDQS_P")
			(pinfunction "PB22A")
			(pintype "bidirectional")
		)
		(pad "R6" smd circle
			(at -2 5.2 180)
			(size 0.45 0.45)
			(layers "F.Cu" "F.Mask" "F.Paste")
			(net 222 "/DDR3/DDR3_DQ3")
			(pinfunction "PB26B")
			(pintype "bidirectional")
		)
		(pad "R7" smd circle
			(at -1.2 5.2 180)
			(size 0.45 0.45)
			(layers "F.Cu" "F.Mask" "F.Paste")
			(net 232 "/DDR3/DDR3_LDM")
			(pinfunction "PB28B")
			(pintype "bidirectional")
		)
		(pad "R8" smd circle
			(at -0.4 5.2 180)
			(size 0.45 0.45)
			(layers "F.Cu" "F.Mask" "F.Paste")
			(net 1 "GND")
			(pinfunction "PB42A")
			(pintype "bidirectional")
		)
		(pad "R9" smd circle
			(at 0.4 5.2 180)
			(size 0.45 0.45)
			(layers "F.Cu" "F.Mask" "F.Paste")
			(net 1 "GND")
			(pinfunction "PB44A/PCLKT4_0")
			(pintype "bidirectional")
		)
		(pad "R10" smd circle
			(at 1.2 5.2 180)
			(size 0.45 0.45)
			(layers "F.Cu" "F.Mask" "F.Paste")
			(net 240 "/DDR3/DDR3_DQ13")
			(pinfunction "PB56B/ADC_CN7\n")
			(pintype "bidirectional")
		)
		(pad "R11" smd circle
			(at 2 5.2 180)
			(size 0.45 0.45)
			(layers "F.Cu" "F.Mask" "F.Paste")
			(net 5 "Vref")
			(pinfunction "PB54A/PCLKT3_0/VREF3_1/ADC_CP5")
			(pintype "bidirectional")
		)
		(pad "R12" smd circle
			(at 2.8 5.2 180)
			(size 0.45 0.45)
			(layers "F.Cu" "F.Mask" "F.Paste")
			(net 227 "/DDR3/DDR3_UDQS_P")
			(pinfunction "PB60A/ADC_CP9")
			(pintype "bidirectional")
		)
		(pad "R13" smd circle
			(at 3.6 5.2 180)
			(size 0.45 0.45)
			(layers "F.Cu" "F.Mask" "F.Paste")
			(net 228 "/DDR3/DDR3_DQ11")
			(pinfunction "PB62A/ADC_CP10")
			(pintype "bidirectional")
		)
		(pad "R14" smd circle
			(at 4.4 5.2 180)
			(size 0.45 0.45)
			(layers "F.Cu" "F.Mask" "F.Paste")
			(net 229 "/DDR3/DDR3_DQ12")
			(pinfunction "PB62B/ADC_CN10")
			(pintype "bidirectional")
		)
		(pad "R15" smd circle
			(at 5.2 5.2 180)
			(size 0.45 0.45)
			(layers "F.Cu" "F.Mask" "F.Paste")
			(net 241 "/DDR3/DDR3_DQ14")
			(pinfunction "PB68B/ADC_CN8")
			(pintype "bidirectional")
		)
		(pad "R16" smd circle
			(at 6 5.2 180)
			(size 0.45 0.45)
			(layers "F.Cu" "F.Mask" "F.Paste")
			(net 226 "/DDR3/DDR3_DQ8")
			(pinfunction "PB68A/ADC_CP8")
			(pintype "bidirectional")
		)
		(pad "T1" smd circle
			(at -6 6 180)
			(size 0.45 0.45)
			(layers "F.Cu" "F.Mask" "F.Paste")
			(net 1 "GND")
			(pinfunction "VSS")
			(pintype "passive")
		)
		(pad "T2" smd circle
			(at -5.2 6 180)
			(size 0.45 0.45)
			(layers "F.Cu" "F.Mask" "F.Paste")
			(net 235 "/DDR3/DDR3_DQ4")
			(pinfunction "PB18B/PCLKC4_3\n")
			(pintype "bidirectional")
		)
		(pad "T3" smd circle
			(at -4.4 6 180)
			(size 0.45 0.45)
			(layers "F.Cu" "F.Mask" "F.Paste")
			(net 236 "/DDR3/DDR3_DQ6")
			(pinfunction "PB20A")
			(pintype "bidirectional")
		)
		(pad "T4" smd circle
			(at -3.6 6 180)
			(size 0.45 0.45)
			(layers "F.Cu" "F.Mask" "F.Paste")
			(net 221 "/DDR3/DDR3_DQ0")
			(pinfunction "PB20B")
			(pintype "bidirectional")
		)
		(pad "T5" smd circle
			(at -2.8 6 180)
			(size 0.45 0.45)
			(layers "F.Cu" "F.Mask" "F.Paste")
			(net 225 "/DDR3/DDR3_DQ7")
			(pinfunction "PB26A")
			(pintype "bidirectional")
		)
	)
)
